# S9S_MB_2U (Grand Teton) — schematic netlist excerpt (pin names and nets, part order shuffled) for the footprints in the layout excerpt that follows; sources: Cadence DE-HDL packaged netlist, KiCad conversion of 03242023_DA0F0TMBIJ0_F0T_Motherboard_J_brd_V01_OCP.brd

R334  Q_RES  10K 1% CHIP  pkg 0402LF  page 127 : A = PD_PIROM_CPU0_ADDR1 ; B = GND
R3071  Q_RES  130 1% CHIP  pkg 0402LF  page 252 : A = LED_PWRGD_P1V8_PCH_AUX ; B = P3V3_AUX

U325  MOSFET_N  BSS138K IC  pkg SMLF  page 306
  DRAIN  = IRQ_UV_DETECT_N
  GATE  = A_P12V_STBY_FPH_GATE
  SOURCE  = GND

(kicad_pcb
	(version 20260206)
	(generator "pcbnew")
	(generator_version "10.0")
	(general
		(thickness 1.6)
		(legacy_teardrops no)
	)
	(paper "A4")
	(title_block
		(title "03242023_DA0F0TMBIJ0_F0T_Motherboard_J_brd_V01_OCP.brd")
		(comment 1 "Grand Teton / footprints 3134-3136 of 6105")
	)
	(layers
		(0 "F.Cu" signal "TOP")
		(4 "In1.Cu" signal "GND")
		(6 "In2.Cu" signal "IN1")
		(8 "In3.Cu" signal "GND1")
		(10 "In4.Cu" signal "IN2")
		(12 "In5.Cu" signal "GND2")
		(14 "In6.Cu" signal "IN3")
		(16 "In7.Cu" signal "GND3")
		(18 "In8.Cu" signal "VCC")
		(20 "In9.Cu" signal "VCC1")
		(22 "In10.Cu" signal "GND4")
		(24 "In11.Cu" signal "IN4")
		(26 "In12.Cu" signal "GND5")
		(28 "In13.Cu" signal "IN5")
		(30 "In14.Cu" signal "GND6")
		(32 "In15.Cu" signal "IN6")
		(34 "In16.Cu" signal "GND7")
		(2 "B.Cu" signal "BOTTOM")
		(9 "F.Adhes" user "F.Adhesive")
		(11 "B.Adhes" user "B.Adhesive")
		(13 "F.Paste" user "Package Geometry/Pastemask Top")
		(15 "B.Paste" user "Package Geometry/Pastemask Bottom")
		(5 "F.SilkS" user "Ref Des/Silkscreen Top")
		(7 "B.SilkS" user "Ref Des/Silkscreen Bottom")
		(1 "F.Mask" user "Board Geometry/Soldermask Top")
		(3 "B.Mask" user "Board Geometry/Soldermask Bottom")
		(17 "Dwgs.User" user "User.Drawings")
		(19 "Cmts.User" user "User.Comments")
		(21 "Eco1.User" user "User.Eco1")
		(23 "Eco2.User" user "User.Eco2")
		(25 "Edge.Cuts" user "Board Geometry/Outline")
		(27 "Margin" user)
		(31 "F.CrtYd" user "Package Geometry/Place Bound Top")
		(29 "B.CrtYd" user "Package Geometry/Place Bound Bottom")
		(35 "F.Fab" user "Ref Des/Assembly Top")
		(33 "B.Fab" user "Ref Des/Assembly Bottom")
	)
	(footprint ""
		(layer "F.Cu")
		(at 406.124664 -368.826034)
		(property "Reference" "R334"
			(at 0 0 0)
			(layer "F.SilkS")
			(hide yes)
			(effects
				(font
					(size 1.27 1.27)
				)
			)
		)
		(property "Value" ""
			(at 0 0 0)
			(layer "F.Fab")
			(effects
				(font
					(size 1.27 1.27)
				)
			)
		)
		(duplicate_pad_numbers_are_jumpers no)
		(fp_line
			(start -0.7874 -0.4064)
			(end 0.7874 -0.4064)
			(stroke
				(width 0.1524)
				(type default)
			)
			(layer "F.SilkS")
		)
		(fp_line
			(start -0.7874 0.4064)
			(end -0.7874 -0.4064)
			(stroke
				(width 0.1524)
				(type default)
			)
			(layer "F.SilkS")
		)
		(fp_line
			(start 0.7874 -0.4064)
			(end 0.7874 0.4064)
			(stroke
				(width 0.1524)
				(type default)
			)
			(layer "F.SilkS")
		)
		(fp_line
			(start 0.7874 0.4064)
			(end -0.7874 0.4064)
			(stroke
				(width 0.1524)
				(type default)
			)
			(layer "F.SilkS")
		)
		(fp_line
			(start -0.67945 -0.305054)
			(end -0.12065 -0.305054)
			(stroke
				(width 0.1)
				(type default)
			)
			(layer "F.Fab")
		)
		(fp_line
			(start -0.67945 0.3048)
			(end -0.67945 -0.305054)
			(stroke
				(width 0.1)
				(type default)
			)
			(layer "F.Fab")
		)
		(fp_line
			(start -0.12065 -0.305054)
			(end -0.12065 -0.2794)
			(stroke
				(width 0.1)
				(type default)
			)
			(layer "F.Fab")
		)
		(fp_line
			(start -0.12065 -0.2794)
			(end 0.12065 -0.2794)
			(stroke
				(width 0.1)
				(type default)
			)
			(layer "F.Fab")
		)
		(fp_line
			(start -0.12065 0.2794)
			(end -0.12065 0.3048)
			(stroke
				(width 0.1)
				(type default)
			)
			(layer "F.Fab")
		)
		(fp_line
			(start -0.12065 0.3048)
			(end -0.67945 0.3048)
			(stroke
				(width 0.1)
				(type default)
			)
			(layer "F.Fab")
		)
		(fp_line
			(start 0.120396 0.2794)
			(end -0.12065 0.2794)
			(stroke
				(width 0.1)
				(type default)
			)
			(layer "F.Fab")
		)
		(fp_line
			(start 0.120396 0.3048)
			(end 0.120396 0.2794)
			(stroke
				(width 0.1)
				(type default)
			)
			(layer "F.Fab")
		)
		(fp_line
			(start 0.12065 -0.3048)
			(end 0.67945 -0.3048)
			(stroke
				(width 0.1)
				(type default)
			)
			(layer "F.Fab")
		)
		(fp_line
			(start 0.12065 -0.2794)
			(end 0.12065 -0.3048)
			(stroke
				(width 0.1)
				(type default)
			)
			(layer "F.Fab")
		)
		(fp_line
			(start 0.67945 -0.3048)
			(end 0.67945 0.3048)
			(stroke
				(width 0.1)
				(type default)
			)
			(layer "F.Fab")
		)
		(fp_line
			(start 0.67945 0.3048)
			(end 0.120396 0.3048)
			(stroke
				(width 0.1)
				(type default)
			)
			(layer "F.Fab")
		)
		(pad "1" smd circle
			(at -0.40005 0)
			(size 0 0)
			(layers "F.Cu" "F.Mask" "F.Paste")
			(net "PD_PIROM_CPU0_ADDR1")
		)
		(pad "2" smd circle
			(at 0.40005 0)
			(size 0 0)
			(layers "F.Cu" "F.Mask" "F.Paste")
			(net "GND")
		)
	)
	(footprint ""
		(layer "F.Cu")
		(at 215.392 -96.103948)
		(property "Reference" "U325"
			(at -5.08 1.04267 0)
			(unlocked yes)
			(layer "F.SilkS")
			(effects
				(font
					(size 0.7874 0.5842)
					(thickness 0.1524)
				)
			)
		)
		(property "Value" ""
			(at 0 0 0)
			(layer "F.Fab")
			(effects
				(font
					(size 1.27 1.27)
				)
			)
		)
		(duplicate_pad_numbers_are_jumpers no)
		(fp_line
			(start -1.949958 -1.610106)
			(end 1.949958 -1.610106)
			(stroke
				(width 0.1524)
				(type default)
			)
			(layer "F.SilkS")
		)
		(fp_line
			(start -1.949958 1.610106)
			(end -1.949958 -1.610106)
			(stroke
				(width 0.1524)
				(type default)
			)
			(layer "F.SilkS")
		)
		(fp_line
			(start 1.949958 -1.560068)
			(end 1.949958 1.610106)
			(stroke
				(width 0.1524)
				(type default)
			)
			(layer "F.SilkS")
		)
		(fp_line
			(start 1.949958 1.610106)
			(end -1.949958 1.610106)
			(stroke
				(width 0.1524)
				(type default)
			)
			(layer "F.SilkS")
		)
		(fp_line
			(start -0.750062 -1.560068)
			(end 0.750062 -1.560068)
			(stroke
				(width 0.1)
				(type default)
			)
			(layer "F.Fab")
		)
		(fp_line
			(start -0.750062 1.560068)
			(end -0.750062 -1.560068)
			(stroke
				(width 0.1)
				(type default)
			)
			(layer "F.Fab")
		)
		(fp_line
			(start 0.750062 -1.560068)
			(end 0.750062 1.560068)
			(stroke
				(width 0.1)
				(type default)
			)
			(layer "F.Fab")
		)
		(fp_line
			(start 0.750062 1.560068)
			(end -0.750062 1.560068)
			(stroke
				(width 0.1)
				(type default)
			)
			(layer "F.Fab")
		)
		(pad "D" smd rect
			(at 1.100074 0 270)
			(size 1.016 1.4224)
			(layers "F.Cu" "F.Mask" "F.Paste")
			(net "IRQ_UV_DETECT_N")
		)
		(pad "G" smd rect
			(at -1.100074 -0.94996 270)
			(size 1.016 1.4224)
			(layers "F.Cu" "F.Mask" "F.Paste")
			(net "A_P12V_STBY_FPH_GATE")
		)
		(pad "S" smd rect
			(at -1.100074 0.94996 270)
			(size 1.016 1.4224)
			(layers "F.Cu" "F.Mask" "F.Paste")
			(net "GND")
		)
	)
	(footprint ""
		(layer "F.Cu")
		(at 109.144308 -74.863452 -90)
		(property "Reference" "R3071"
			(at 0 0 270)
			(layer "F.SilkS")
			(hide yes)
			(effects
				(font
					(size 1.27 1.27)
				)
			)
		)
		(property "Value" ""
			(at 0 0 270)
			(layer "F.Fab")
			(effects
				(font
					(size 1.27 1.27)
				)
			)
		)
		(duplicate_pad_numbers_are_jumpers no)
		(fp_line
			(start -0.7874 0.4064)
			(end -0.7874 -0.4064)
			(stroke
				(width 0.1524)
				(type default)
			)
			(layer "F.SilkS")
		)
		(fp_line
			(start 0.7874 0.4064)
			(end -0.7874 0.4064)
			(stroke
				(width 0.1524)
				(type default)
			)
			(layer "F.SilkS")
		)
		(fp_line
			(start -0.7874 -0.4064)
			(end 0.7874 -0.4064)
			(stroke
				(width 0.1524)
				(type default)
			)
			(layer "F.SilkS")
		)
		(fp_line
			(start 0.7874 -0.4064)
			(end 0.7874 0.4064)
			(stroke
				(width 0.1524)
				(type default)
			)
			(layer "F.SilkS")
		)
		(fp_line
			(start -0.67945 0.3048)
			(end -0.67945 -0.305054)
			(stroke
				(width 0.1)
				(type default)
			)
			(layer "F.Fab")
		)
		(fp_line
			(start -0.12065 0.3048)
			(end -0.67945 0.3048)
			(stroke
				(width 0.1)
				(type default)
			)
			(layer "F.Fab")
		)
		(fp_line
			(start 0.120396 0.3048)
			(end 0.120396 0.2794)
			(stroke
				(width 0.1)
				(type default)
			)
			(layer "F.Fab")
		)
		(fp_line
			(start 0.67945 0.3048)
			(end 0.120396 0.3048)
			(stroke
				(width 0.1)
				(type default)
			)
			(layer "F.Fab")
		)
		(fp_line
			(start -0.12065 0.2794)
			(end -0.12065 0.3048)
			(stroke
				(width 0.1)
				(type default)
			)
			(layer "F.Fab")
		)
		(fp_line
			(start 0.120396 0.2794)
			(end -0.12065 0.2794)
			(stroke
				(width 0.1)
				(type default)
			)
			(layer "F.Fab")
		)
		(fp_line
			(start -0.12065 -0.2794)
			(end 0.12065 -0.2794)
			(stroke
				(width 0.1)
				(type default)
			)
			(layer "F.Fab")
		)
		(fp_line
			(start 0.12065 -0.2794)
			(end 0.12065 -0.3048)
			(stroke
				(width 0.1)
				(type default)
			)
			(layer "F.Fab")
		)
		(fp_line
			(start 0.12065 -0.3048)
			(end 0.67945 -0.3048)
			(stroke
				(width 0.1)
				(type default)
			)
			(layer "F.Fab")
		)
		(fp_line
			(start 0.67945 -0.3048)
			(end 0.67945 0.3048)
			(stroke
				(width 0.1)
				(type default)
			)
			(layer "F.Fab")
		)
		(fp_line
			(start -0.67945 -0.305054)
			(end -0.12065 -0.305054)
			(stroke
				(width 0.1)
				(type default)
			)
			(layer "F.Fab")
		)
		(fp_line
			(start -0.12065 -0.305054)
			(end -0.12065 -0.2794)
			(stroke
				(width 0.1)
				(type default)
			)
			(layer "F.Fab")
		)
		(pad "1" smd circle
			(at -0.40005 0 270)
			(size 0 0)
			(layers "F.Cu" "F.Mask" "F.Paste")
			(net "LED_PWRGD_P1V8_PCH_AUX")
		)
		(pad "2" smd circle
			(at 0.40005 0 270)
			(size 0 0)
			(layers "F.Cu" "F.Mask" "F.Paste")
			(net "P3V3_AUX")
		)
	)
)
